FILE_TYPE=LIBRARY_PARTS;
primitive 'SN74AUC2G66DCTR';
  pin
    '1A':
      PIN_NUMBER='(1)';
      BIDIRECTIONAL='TRUE';
      INPUT_LOAD='(-0.01,0.01)';
      OUTPUT_LOAD='(1.0,-1.0)';
    '1C':
      PIN_NUMBER='(7)';
      BIDIRECTIONAL='TRUE';
      INPUT_LOAD='(-0.01,0.01)';
      OUTPUT_LOAD='(1.0,-1.0)';
    '2A':
      PIN_NUMBER='(5)';
      BIDIRECTIONAL='TRUE';
      INPUT_LOAD='(-0.01,0.01)';
      OUTPUT_LOAD='(1.0,-1.0)';
    '2C':
      PIN_NUMBER='(3)';
      BIDIRECTIONAL='TRUE';
      INPUT_LOAD='(-0.01,0.01)';
      OUTPUT_LOAD='(1.0,-1.0)';
    'VCC':
      PIN_NUMBER='(8)';
      PINUSE='POWER';
      NO_LOAD_CHECK='Both';
      NO_IO_CHECK='Both';
      NO_ASSERT_CHECK='TRUE';
      NO_DIR_CHECK='TRUE';
      ALLOW_CONNECT='TRUE';
    'GND':
      PIN_NUMBER='(4)';
      PINUSE='POWER';
      NO_LOAD_CHECK='Both';
      NO_IO_CHECK='Both';
      NO_ASSERT_CHECK='TRUE';
      NO_DIR_CHECK='TRUE';
      ALLOW_CONNECT='TRUE';
    '1B':
      PIN_NUMBER='(2)';
      BIDIRECTIONAL='TRUE';
      INPUT_LOAD='(-0.01,0.01)';
      OUTPUT_LOAD='(1.0,-1.0)';
    '2B':
      PIN_NUMBER='(6)';
      BIDIRECTIONAL='TRUE';
      INPUT_LOAD='(-0.01,0.01)';
      OUTPUT_LOAD='(1.0,-1.0)';
  end_pin;
  body
    PART_NAME='SN74AUC2G66DCTR';
    BODY_NAME='SN74AUC2G66DCTR';
    PHYS_DES_PREFIX='U';
    CLASS='IC';
  end_body;
end_primitive;

END.
